(kicad_pcb
	(version 20260206)
	(generator "pcbnew")
	(generator_version "10.0")
	(general
		(thickness 1.6)
		(legacy_teardrops no)
	)
	(paper "A4")
	(title_block
		(title "Wiwynn_Tioga_Pass_MB.brd")
		(comment 1 "Tioga Pass / footprints 1233-1240 of 4770")
	)
	(layers
		(0 "F.Cu" signal "TOP")
		(4 "In1.Cu" signal "L2GND")
		(6 "In2.Cu" signal "L3")
		(8 "In3.Cu" signal "L4GND")
		(10 "In4.Cu" signal "L5")
		(12 "In5.Cu" signal "L6GND")
		(14 "In6.Cu" signal "L7VCC")
		(16 "In7.Cu" signal "L8VCC")
		(18 "In8.Cu" signal "L9GND")
		(20 "In9.Cu" signal "L10")
		(22 "In10.Cu" signal "L11GND")
		(24 "In11.Cu" signal "L12")
		(26 "In12.Cu" signal "L13GND")
		(2 "B.Cu" signal "BOTTOM")
		(9 "F.Adhes" user "F.Adhesive")
		(11 "B.Adhes" user "B.Adhesive")
		(13 "F.Paste" user "Package Geometry/Pastemask Top")
		(15 "B.Paste" user "Package Geometry/Pastemask Bottom")
		(5 "F.SilkS" user "Ref Des/Silkscreen Top")
		(7 "B.SilkS" user "Ref Des/Silkscreen Bottom")
		(1 "F.Mask" user "Board Geometry/Soldermask Top")
		(3 "B.Mask" user "Board Geometry/Soldermask Bottom")
		(17 "Dwgs.User" user "User.Drawings")
		(19 "Cmts.User" user "User.Comments")
		(21 "Eco1.User" user "User.Eco1")
		(23 "Eco2.User" user "User.Eco2")
		(25 "Edge.Cuts" user "Board Geometry/Outline")
		(27 "Margin" user)
		(31 "F.CrtYd" user "Package Geometry/Place Bound Top")
		(29 "B.CrtYd" user "Package Geometry/Place Bound Bottom")
		(35 "F.Fab" user "Ref Des/Assembly Top")
		(33 "B.Fab" user "Ref Des/Assembly Bottom")
	)
	(footprint ""
		(layer "F.Cu")
		(at 488.3912 -50.6857)
		(property "Reference" "R9E3"
			(at 0 0 0)
			(layer "F.SilkS")
			(hide yes)
			(effects
				(font
					(size 1.27 1.27)
				)
			)
		)
		(property "Value" ""
			(at 0 0 0)
			(layer "F.Fab")
			(effects
				(font
					(size 1.27 1.27)
				)
			)
		)
		(duplicate_pad_numbers_are_jumpers no)
		(fp_poly
			(pts
				(xy -0.2794 -0.1016) (xy 0.2794 -0.1016) (xy 0.2794 0.9906) (xy -0.2794 0.9906)
			)
			(stroke
				(width 0)
				(type default)
			)
			(fill no)
			(layer "F.CrtYd")
		)
		(fp_line
			(start -0.2794 -0.1016)
			(end -0.2794 0.9906)
			(stroke
				(width 0.1)
				(type default)
			)
			(layer "F.Fab")
		)
		(fp_line
			(start -0.2794 0.9906)
			(end 0.2794 0.9906)
			(stroke
				(width 0.1)
				(type default)
			)
			(layer "F.Fab")
		)
		(fp_line
			(start 0.2794 -0.1016)
			(end -0.2794 -0.1016)
			(stroke
				(width 0.1)
				(type default)
			)
			(layer "F.Fab")
		)
		(fp_line
			(start 0.2794 0.9906)
			(end 0.2794 -0.1016)
			(stroke
				(width 0.1)
				(type default)
			)
			(layer "F.Fab")
		)
		(pad "1" smd rect
			(at 0 0)
			(size 0.508 0.508)
			(layers "F.Cu" "F.Mask" "F.Paste")
			(net "P3V3_STBY")
		)
		(pad "2" smd rect
			(at 0 0.889)
			(size 0.508 0.508)
			(layers "F.Cu" "F.Mask" "F.Paste")
			(net "PU_JTAG_SPRV_TMS")
		)
		(zone
			(layer "F.Cu")
			(hatch none 0.5)
			(connect_pads
				(clearance 0)
			)
			(min_thickness 0.25)
			(keepout
				(tracks allowed)
				(vias not_allowed)
				(pads allowed)
				(copperpour not_allowed)
				(footprints allowed)
			)
			(placement
				(enabled no)
				(sheetname "")
			)
			(fill
				(thermal_gap 0.5)
				(thermal_bridge_width 0.5)
				(island_removal_mode 0)
			)
			(polygon
				(pts
					(xy 488.1372 -50.4317) (xy 488.6452 -50.4317) (xy 488.6452 -50.0507) (xy 488.1372 -50.0507)
				)
			)
		)
		(zone
			(layer "F.Cu")
			(hatch none 0.5)
			(connect_pads
				(clearance 0)
			)
			(min_thickness 0.25)
			(keepout
				(tracks not_allowed)
				(vias allowed)
				(pads allowed)
				(copperpour not_allowed)
				(footprints allowed)
			)
			(placement
				(enabled no)
				(sheetname "")
			)
			(fill
				(thermal_gap 0.5)
				(thermal_bridge_width 0.5)
				(island_removal_mode 0)
			)
			(polygon
				(pts
					(xy 488.1372 -50.0507) (xy 488.6452 -50.0507) (xy 488.6452 -50.4317) (xy 488.1372 -50.4317)
				)
			)
		)
	)
	(footprint ""
		(layer "F.Cu")
		(at 417.83 -86.4235)
		(property "Reference" "C8E1"
			(at 0 0 0)
			(layer "F.SilkS")
			(hide yes)
			(effects
				(font
					(size 1.27 1.27)
				)
			)
		)
		(property "Value" ""
			(at 0 0 0)
			(layer "F.Fab")
			(effects
				(font
					(size 1.27 1.27)
				)
			)
		)
		(duplicate_pad_numbers_are_jumpers no)
		(fp_poly
			(pts
				(xy 0.3048 -0.1016) (xy 0.3048 0.9906) (xy -0.3048 0.9906) (xy -0.3048 -0.1016)
			)
			(stroke
				(width 0)
				(type default)
			)
			(fill no)
			(layer "F.CrtYd")
		)
		(fp_line
			(start -0.3048 -0.1016)
			(end -0.3048 0.9906)
			(stroke
				(width 0.1)
				(type default)
			)
			(layer "F.Fab")
		)
		(fp_line
			(start -0.3048 0.9906)
			(end 0.3048 0.9906)
			(stroke
				(width 0.1)
				(type default)
			)
			(layer "F.Fab")
		)
		(fp_line
			(start 0.3048 -0.1016)
			(end -0.3048 -0.1016)
			(stroke
				(width 0.1)
				(type default)
			)
			(layer "F.Fab")
		)
		(fp_line
			(start 0.3048 0.9906)
			(end 0.3048 -0.1016)
			(stroke
				(width 0.1)
				(type default)
			)
			(layer "F.Fab")
		)
		(pad "1" smd rect
			(at 0 0)
			(size 0.508 0.508)
			(layers "F.Cu" "F.Mask" "F.Paste")
			(net "P3V3_STBY")
		)
		(pad "2" smd rect
			(at 0 0.889)
			(size 0.508 0.508)
			(layers "F.Cu" "F.Mask" "F.Paste")
			(net "GND")
		)
		(zone
			(layer "F.Cu")
			(hatch none 0.5)
			(connect_pads
				(clearance 0)
			)
			(min_thickness 0.25)
			(keepout
				(tracks allowed)
				(vias not_allowed)
				(pads allowed)
				(copperpour not_allowed)
				(footprints allowed)
			)
			(placement
				(enabled no)
				(sheetname "")
			)
			(fill
				(thermal_gap 0.5)
				(thermal_bridge_width 0.5)
				(island_removal_mode 0)
			)
			(polygon
				(pts
					(xy 417.576 -86.1695) (xy 418.084 -86.1695) (xy 418.084 -85.7885) (xy 417.576 -85.7885)
				)
			)
		)
		(zone
			(layer "F.Cu")
			(hatch none 0.5)
			(connect_pads
				(clearance 0)
			)
			(min_thickness 0.25)
			(keepout
				(tracks not_allowed)
				(vias allowed)
				(pads allowed)
				(copperpour not_allowed)
				(footprints allowed)
			)
			(placement
				(enabled no)
				(sheetname "")
			)
			(fill
				(thermal_gap 0.5)
				(thermal_bridge_width 0.5)
				(island_removal_mode 0)
			)
			(polygon
				(pts
					(xy 417.576 -85.7885) (xy 418.084 -85.7885) (xy 418.084 -86.1695) (xy 417.576 -86.1695)
				)
			)
		)
	)
	(footprint ""
		(layer "F.Cu")
		(at 40.036496 -65.159382)
		(property "Reference" "L1D3"
			(at 3.378708 -4.251706 0)
			(unlocked yes)
			(layer "F.SilkS")
			(effects
				(font
					(size 0.4064 0.254)
					(thickness 0.1524)
				)
			)
		)
		(property "Value" ""
			(at 0 0 0)
			(layer "F.Fab")
			(effects
				(font
					(size 1.27 1.27)
				)
			)
		)
		(duplicate_pad_numbers_are_jumpers no)
		(fp_line
			(start -1.1303 -3.199892)
			(end 8.3693 -3.199892)
			(stroke
				(width 0.1524)
				(type default)
			)
			(layer "F.SilkS")
		)
		(fp_line
			(start -1.1303 -1.6637)
			(end -1.1303 -3.199892)
			(stroke
				(width 0.1524)
				(type default)
			)
			(layer "F.SilkS")
		)
		(fp_line
			(start -1.1303 3.199892)
			(end -1.1303 1.6637)
			(stroke
				(width 0.1524)
				(type default)
			)
			(layer "F.SilkS")
		)
		(fp_line
			(start 8.3693 -3.199892)
			(end 8.3693 -1.6637)
			(stroke
				(width 0.1524)
				(type default)
			)
			(layer "F.SilkS")
		)
		(fp_line
			(start 8.3693 1.6637)
			(end 8.3693 3.199892)
			(stroke
				(width 0.1524)
				(type default)
			)
			(layer "F.SilkS")
		)
		(fp_line
			(start 8.3693 3.199892)
			(end -1.1303 3.199892)
			(stroke
				(width 0.1524)
				(type default)
			)
			(layer "F.SilkS")
		)
		(fp_rect
			(start -1.1303 3.199892)
			(end 8.3693 -3.199892)
			(stroke
				(width 0)
				(type default)
			)
			(fill no)
			(layer "F.CrtYd")
		)
		(fp_line
			(start -1.1303 -3.199892)
			(end 8.3693 -3.199892)
			(stroke
				(width 0.1)
				(type default)
			)
			(layer "F.Fab")
		)
		(fp_line
			(start -1.1303 3.199892)
			(end -1.1303 -3.199892)
			(stroke
				(width 0.1)
				(type default)
			)
			(layer "F.Fab")
		)
		(fp_line
			(start 8.3693 -3.199892)
			(end 8.3693 3.199892)
			(stroke
				(width 0.1)
				(type default)
			)
			(layer "F.Fab")
		)
		(fp_line
			(start 8.3693 3.199892)
			(end -1.1303 3.199892)
			(stroke
				(width 0.1)
				(type default)
			)
			(layer "F.Fab")
		)
		(pad "1" smd rect
			(at 0 0)
			(size 3.683 2.667)
			(layers "F.Cu" "F.Mask" "F.Paste")
			(net "VR_PVCCIN_CPU1_PHASE2")
		)
		(pad "2" smd rect
			(at 7.239 0)
			(size 3.683 2.667)
			(layers "F.Cu" "F.Mask" "F.Paste")
			(net "PVCCIN_CPU1")
		)
	)
	(footprint ""
		(layer "F.Cu")
		(at 455.422 -38.735)
		(property "Reference" "R9E21"
			(at 0 0 0)
			(layer "F.SilkS")
			(hide yes)
			(effects
				(font
					(size 1.27 1.27)
				)
			)
		)
		(property "Value" ""
			(at 0 0 0)
			(layer "F.Fab")
			(effects
				(font
					(size 1.27 1.27)
				)
			)
		)
		(duplicate_pad_numbers_are_jumpers no)
		(fp_poly
			(pts
				(xy -0.2794 -0.1016) (xy 0.2794 -0.1016) (xy 0.2794 0.9906) (xy -0.2794 0.9906)
			)
			(stroke
				(width 0)
				(type default)
			)
			(fill no)
			(layer "F.CrtYd")
		)
		(fp_line
			(start -0.2794 -0.1016)
			(end -0.2794 0.9906)
			(stroke
				(width 0.1)
				(type default)
			)
			(layer "F.Fab")
		)
		(fp_line
			(start -0.2794 0.9906)
			(end 0.2794 0.9906)
			(stroke
				(width 0.1)
				(type default)
			)
			(layer "F.Fab")
		)
		(fp_line
			(start 0.2794 -0.1016)
			(end -0.2794 -0.1016)
			(stroke
				(width 0.1)
				(type default)
			)
			(layer "F.Fab")
		)
		(fp_line
			(start 0.2794 0.9906)
			(end 0.2794 -0.1016)
			(stroke
				(width 0.1)
				(type default)
			)
			(layer "F.Fab")
		)
		(pad "1" smd rect
			(at 0 0)
			(size 0.508 0.508)
			(layers "F.Cu" "F.Mask" "F.Paste")
			(net "P3V3_STBY")
		)
		(pad "2" smd rect
			(at 0 0.889)
			(size 0.508 0.508)
			(layers "F.Cu" "F.Mask" "F.Paste")
			(net "FM_HEARTBEAT_LED")
		)
		(zone
			(layer "F.Cu")
			(hatch none 0.5)
			(connect_pads
				(clearance 0)
			)
			(min_thickness 0.25)
			(keepout
				(tracks allowed)
				(vias not_allowed)
				(pads allowed)
				(copperpour not_allowed)
				(footprints allowed)
			)
			(placement
				(enabled no)
				(sheetname "")
			)
			(fill
				(thermal_gap 0.5)
				(thermal_bridge_width 0.5)
				(island_removal_mode 0)
			)
			(polygon
				(pts
					(xy 455.168 -38.481) (xy 455.676 -38.481) (xy 455.676 -38.1) (xy 455.168 -38.1)
				)
			)
		)
		(zone
			(layer "F.Cu")
			(hatch none 0.5)
			(connect_pads
				(clearance 0)
			)
			(min_thickness 0.25)
			(keepout
				(tracks not_allowed)
				(vias allowed)
				(pads allowed)
				(copperpour not_allowed)
				(footprints allowed)
			)
			(placement
				(enabled no)
				(sheetname "")
			)
			(fill
				(thermal_gap 0.5)
				(thermal_bridge_width 0.5)
				(island_removal_mode 0)
			)
			(polygon
				(pts
					(xy 455.168 -38.1) (xy 455.676 -38.1) (xy 455.676 -38.481) (xy 455.168 -38.481)
				)
			)
		)
	)
	(footprint ""
		(layer "F.Cu")
		(at 404.43658 -141.783816 -90)
		(property "Reference" "C8A14"
			(at 0 0 270)
			(layer "F.SilkS")
			(hide yes)
			(effects
				(font
					(size 1.27 1.27)
				)
			)
		)
		(property "Value" ""
			(at 0 0 270)
			(layer "F.Fab")
			(effects
				(font
					(size 1.27 1.27)
				)
			)
		)
		(duplicate_pad_numbers_are_jumpers no)
		(fp_poly
			(pts
				(xy -0.7239 -0.2159) (xy 0.7239 -0.2159) (xy 0.7239 1.9939) (xy -0.7239 1.9939)
			)
			(stroke
				(width 0)
				(type default)
			)
			(fill no)
			(layer "F.CrtYd")
		)
		(fp_line
			(start -0.7239 1.9939)
			(end 0.7239 1.9939)
			(stroke
				(width 0.1)
				(type default)
			)
			(layer "F.Fab")
		)
		(fp_line
			(start 0.7239 1.9939)
			(end 0.7239 -0.2159)
			(stroke
				(width 0.1)
				(type default)
			)
			(layer "F.Fab")
		)
		(fp_line
			(start -0.7239 -0.2159)
			(end -0.7239 1.9939)
			(stroke
				(width 0.1)
				(type default)
			)
			(layer "F.Fab")
		)
		(fp_line
			(start 0.7239 -0.2159)
			(end -0.7239 -0.2159)
			(stroke
				(width 0.1)
				(type default)
			)
			(layer "F.Fab")
		)
		(pad "1" smd rect
			(at 0 0 270)
			(size 1.27 1.016)
			(layers "F.Cu" "F.Mask" "F.Paste")
			(net "P1V8_PCH_STBY")
		)
		(pad "2" smd rect
			(at 0 1.778 270)
			(size 1.27 1.016)
			(layers "F.Cu" "F.Mask" "F.Paste")
			(net "GND")
		)
		(zone
			(layer "F.Cu")
			(hatch none 0.5)
			(connect_pads
				(clearance 0)
			)
			(min_thickness 0.25)
			(keepout
				(tracks not_allowed)
				(vias allowed)
				(pads allowed)
				(copperpour not_allowed)
				(footprints allowed)
			)
			(placement
				(enabled no)
				(sheetname "")
			)
			(fill
				(thermal_gap 0.5)
				(thermal_bridge_width 0.5)
				(island_removal_mode 0)
			)
			(polygon
				(pts
					(xy 403.92858 -142.418816) (xy 403.92858 -141.148816) (xy 403.16658 -141.148816) (xy 403.16658 -142.418816)
				)
			)
		)
	)
	(footprint ""
		(layer "F.Cu")
		(at 369.333526 -104.309164 90)
		(property "Reference" "R7C4"
			(at 0 0 90)
			(layer "F.SilkS")
			(hide yes)
			(effects
				(font
					(size 1.27 1.27)
				)
			)
		)
		(property "Value" ""
			(at 0 0 90)
			(layer "F.Fab")
			(effects
				(font
					(size 1.27 1.27)
				)
			)
		)
		(duplicate_pad_numbers_are_jumpers no)
		(fp_poly
			(pts
				(xy -0.2794 -0.1016) (xy 0.2794 -0.1016) (xy 0.2794 0.9906) (xy -0.2794 0.9906)
			)
			(stroke
				(width 0)
				(type default)
			)
			(fill no)
			(layer "F.CrtYd")
		)
		(fp_line
			(start 0.2794 -0.1016)
			(end -0.2794 -0.1016)
			(stroke
				(width 0.1)
				(type default)
			)
			(layer "F.Fab")
		)
		(fp_line
			(start -0.2794 -0.1016)
			(end -0.2794 0.9906)
			(stroke
				(width 0.1)
				(type default)
			)
			(layer "F.Fab")
		)
		(fp_line
			(start 0.2794 0.9906)
			(end 0.2794 -0.1016)
			(stroke
				(width 0.1)
				(type default)
			)
			(layer "F.Fab")
		)
		(fp_line
			(start -0.2794 0.9906)
			(end 0.2794 0.9906)
			(stroke
				(width 0.1)
				(type default)
			)
			(layer "F.Fab")
		)
		(pad "1" smd rect
			(at 0 0 90)
			(size 0.508 0.508)
			(layers "F.Cu" "F.Mask" "F.Paste")
			(net "CLK_100M_BMC_PE_R_DP")
		)
		(pad "2" smd rect
			(at 0 0.889 90)
			(size 0.508 0.508)
			(layers "F.Cu" "F.Mask" "F.Paste")
			(net "CLK_100M_BMC_PE_DP")
		)
		(zone
			(layer "F.Cu")
			(hatch none 0.5)
			(connect_pads
				(clearance 0)
			)
			(min_thickness 0.25)
			(keepout
				(tracks allowed)
				(vias not_allowed)
				(pads allowed)
				(copperpour not_allowed)
				(footprints allowed)
			)
			(placement
				(enabled no)
				(sheetname "")
			)
			(fill
				(thermal_gap 0.5)
				(thermal_bridge_width 0.5)
				(island_removal_mode 0)
			)
			(polygon
				(pts
					(xy 369.587526 -104.055164) (xy 369.587526 -104.563164) (xy 369.968526 -104.563164) (xy 369.968526 -104.055164)
				)
			)
		)
		(zone
			(layer "F.Cu")
			(hatch none 0.5)
			(connect_pads
				(clearance 0)
			)
			(min_thickness 0.25)
			(keepout
				(tracks not_allowed)
				(vias allowed)
				(pads allowed)
				(copperpour not_allowed)
				(footprints allowed)
			)
			(placement
				(enabled no)
				(sheetname "")
			)
			(fill
				(thermal_gap 0.5)
				(thermal_bridge_width 0.5)
				(island_removal_mode 0)
			)
			(polygon
				(pts
					(xy 369.968526 -104.055164) (xy 369.968526 -104.563164) (xy 369.587526 -104.563164) (xy 369.587526 -104.055164)
				)
			)
		)
	)
	(footprint ""
		(layer "F.Cu")
		(at 183.795416 -59.238896 180)
		(property "Reference" "C4E14"
			(at 0 0 180)
			(layer "F.SilkS")
			(hide yes)
			(effects
				(font
					(size 1.27 1.27)
				)
			)
		)
		(property "Value" "*"
			(at -0.0762 -6.2357 180)
			(unlocked yes)
			(layer "F.Fab")
			(hide yes)
			(effects
				(font
					(size 1.27 1.016)
					(thickness 0.1524)
				)
			)
		)
		(property "Device Type" "SC22U16V5MX-4-GP_SMD-BCG5-SC22A"
			(at -0.0762 -8.2677 180)
			(unlocked yes)
			(layer "F.Fab")
			(hide yes)
			(effects
				(font
					(size 1.27 1.016)
					(thickness 0.1524)
				)
			)
		)
		(duplicate_pad_numbers_are_jumpers no)
		(fp_line
			(start 0.635 0)
			(end -0.635 0)
			(stroke
				(width 0.508)
				(type default)
			)
			(layer "F.SilkS")
		)
		(fp_rect
			(start -0.9652 1.778)
			(end 0.9652 -1.778)
			(stroke
				(width 0)
				(type default)
			)
			(fill no)
			(layer "F.CrtYd")
		)
		(fp_poly
			(pts
				(xy -0.9652 -1.778) (xy 0.9652 -1.778) (xy 0.9652 1.778) (xy -0.9652 1.778)
			)
			(stroke
				(width 0)
				(type default)
			)
			(fill no)
			(layer "F.Fab")
		)
		(pad "1" smd rect
			(at 0 -0.9652 180)
			(size 1.397 1.143)
			(layers "F.Cu" "F.Mask" "F.Paste")
			(net "VR_FET_SW_P12V_STBY_PVCCIN_CPU0")
		)
		(pad "2" smd rect
			(at 0 0.9652 180)
			(size 1.397 1.143)
			(layers "F.Cu" "F.Mask" "F.Paste")
			(net "GND")
		)
	)
	(footprint ""
		(layer "F.Cu")
		(at 29.036518 -72.03313 -90)
		(property "Reference" "R1D55"
			(at 0 0 270)
			(layer "F.SilkS")
			(hide yes)
			(effects
				(font
					(size 1.27 1.27)
				)
			)
		)
		(property "Value" ""
			(at 0 0 270)
			(layer "F.Fab")
			(effects
				(font
					(size 1.27 1.27)
				)
			)
		)
		(duplicate_pad_numbers_are_jumpers no)
		(fp_poly
			(pts
				(xy -0.2794 -0.1016) (xy 0.2794 -0.1016) (xy 0.2794 0.9906) (xy -0.2794 0.9906)
			)
			(stroke
				(width 0)
				(type default)
			)
			(fill no)
			(layer "F.CrtYd")
		)
		(fp_line
			(start -0.2794 0.9906)
			(end 0.2794 0.9906)
			(stroke
				(width 0.1)
				(type default)
			)
			(layer "F.Fab")
		)
		(fp_line
			(start 0.2794 0.9906)
			(end 0.2794 -0.1016)
			(stroke
				(width 0.1)
				(type default)
			)
			(layer "F.Fab")
		)
		(fp_line
			(start -0.2794 -0.1016)
			(end -0.2794 0.9906)
			(stroke
				(width 0.1)
				(type default)
			)
			(layer "F.Fab")
		)
		(fp_line
			(start 0.2794 -0.1016)
			(end -0.2794 -0.1016)
			(stroke
				(width 0.1)
				(type default)
			)
			(layer "F.Fab")
		)
		(pad "1" smd rect
			(at 0 0 270)
			(size 0.508 0.508)
			(layers "F.Cu" "F.Mask" "F.Paste")
			(net "VR_PVCCIN_CPU1_PH3_OCSET")
		)
		(pad "2" smd rect
			(at 0 0.889 270)
			(size 0.508 0.508)
			(layers "F.Cu" "F.Mask" "F.Paste")
			(net "GND")
		)
		(zone
			(layer "F.Cu")
			(hatch none 0.5)
			(connect_pads
				(clearance 0)
			)
			(min_thickness 0.25)
			(keepout
				(tracks not_allowed)
				(vias allowed)
				(pads allowed)
				(copperpour not_allowed)
				(footprints allowed)
			)
			(placement
				(enabled no)
				(sheetname "")
			)
			(fill
				(thermal_gap 0.5)
				(thermal_bridge_width 0.5)
				(island_removal_mode 0)
			)
			(polygon
				(pts
					(xy 28.401518 -72.28713) (xy 28.401518 -71.77913) (xy 28.782518 -71.77913) (xy 28.782518 -72.28713)
				)
			)
		)
		(zone
			(layer "F.Cu")
			(hatch none 0.5)
			(connect_pads
				(clearance 0)
			)
			(min_thickness 0.25)
			(keepout
				(tracks allowed)
				(vias not_allowed)
				(pads allowed)
				(copperpour not_allowed)
				(footprints allowed)
			)
			(placement
				(enabled no)
				(sheetname "")
			)
			(fill
				(thermal_gap 0.5)
				(thermal_bridge_width 0.5)
				(island_removal_mode 0)
			)
			(polygon
				(pts
					(xy 28.782518 -72.28713) (xy 28.782518 -71.77913) (xy 28.401518 -71.77913) (xy 28.401518 -72.28713)
				)
			)
		)
	)
)
